FILE_TYPE = CONNECTIVITY;
{Allegro Design Entry HDL 16.6-p007 (v16-6-112F) 10/10/2012}
"PAGE_NUMBER" = 199;
0"NC";
1"AGND_HSC\g";
2"AGND_HSC\g";
3"GND\g";
4"AGND_HSC\g";
5"AGND_HSC\g";
6"AGND_HSC\g";
7"GND\g";
8"AGND_HSC\g";
9"AGND_HSC\g";
10"AGND_HSC\g";
11"AGND_HSC\g";
12"AGND_HSC\g";
13"GND\g";
14"AGND_HSC\g";
15"AGND_HSC\g";
16"AGND_HSC\g";
17"GND\g";
18"AGND_HSC\g";
19"AGND_HSC\g";
20"GND\g";
21"AGND_HSC\g";
22"P12V_STBY\g";
23"P12V_STBY\g";
24"P12V_STBY\g";
25"P12V_PSU\g";
26"AGND_HSC\g";
27"AGND_HSC\g";
28"P12V_PSU\g";
29"FM_P12V_HOTSWAP0_EN";
30"A_HSC_VOUT";
31"IRQ_SML1_PMBUS_ALERT_N";
32"PWRGD_P12V_HSC";
33"IRQ_HSC_FAULT_N";
34"A_HSC_TEMP";
35"A_HSC_MOP";
36"A_HSC_HSN";
37"A_HSC_HSP";
38"A_HSC_MON";
39"TP_HSC_ALERT2_N";
40"TP_HSC_MCLK";
41"TP_HSC_MDAT";
42"IRQ_SML1_PMBUS_ALERT_R_N";
43"IRQ_SML1_PMBUS_ALERT_R_N";
44"A_HSC_CSOUT";
45"A_HSC_GATE";
46"PWRGD_P12V_R";
47"A_HSC_ISET";
48"A_HSC_VCAP";
49"A_HSC_OV";
50"A_HSC_UV";
51"A_HSC_PWGIN";
52"A_HSC_PSET";
53"A_HSC_ISTART";
54"P12V_HSC_VCC"VOLTAGE"+12V";
55"FM_P12V_HSC_ADR1";
56"PD_HSC_RETRY_N";
57"TP_HSC_SPISSN";
58"FM_P12V_HSC_ADR2";
59"SMB_3V3SB_HSC_SDA_R";
60"A_HSC_TIMER";
61"SMB_3V3SB_HSC_SCL_R";
62"IRQ_HSC_FAULT_R_N";
63"A_HSC_ISET_S2";
64"A_HSC_LOW_EN";
65"SMB_BMC_PMBUS_STBY_LVC3_SCL";
66"SMB_BMC_PMBUS_STBY_LVC3_SDA";
67"A_HSC_ISET_S";
68"A_HSC_HIGH_EN";
69"A_HSC_OCP_SEL";
%"ADM1278"
"1","(-3250,2575)","0","mstr_controller","I10";
;
CDS_SEC"1"
ROOM"HOT_SWAP"
PACK_TYPE"SM"
SEC_TYPE"SM"
SEC"1"
CDS_LOCATION"EU1D2"
CDS_LIB"mstr_controller"
LOCATION"EU1D2"
MATERIAL"IC"
PART_NUMBER"G99251-001";
"PWRGD"
$PN"18"46;
"FAULT_N"
$PN"6"62;
"EP"
$PN"33"9;
"PGND"
$PN"23"3;
"GND"
$PN"22"14;
"VOUT"
$PN"20"30;
"GATE"
$PN"24"45;
"CSOUT"
$PN"19"44;
"MDAT"
$PN"11"41;
"MCLK"
$PN"10"40;
"GPO2_ALERT2_N"
$PN"14"39;
"GPO1_ALERT1_N_CONV"
$PN"13"42;
"MON"
$PN"26"38;
"MOP"
$PN"29"35;
"HSN"
$PN"27"36;
"HSP"
$PN"28"37;
"TEMP"
$PN"25"34;
"PWGIN"
$PN"21"51;
"SPISS_N"
$PN"9"57;
"ENABLE"
$PN"12"29;
"ADR2"
$PN"8"58;
"ADR1"
$PN"7"55;
"SDA"
$PN"15"59;
"TIMER"
$PN"5"60;
"SCL"
$PN"16"61;
"RETRY_N"
$PN"17"56;
"ISTART"
$PN"4"53;
"PSET"
$PN"1"52;
"ISET"
$PN"3"47;
"OV"
$PN"32"49;
"VCAP"
$PN"2"48;
"UV"
$PN"31"50;
"VCC"
$PN"30"54;
%"RES"
"2","(-5300,800)","0","mstr_discrete","I100";
;
CDS_SEC"1"
SEC_TYPE"0402"
SEC"1"
ROOM"HOT_SWAP"
CDS_LOCATION"R1D40"
CDS_LIB"mstr_discrete"
LOCATION"R1D40"
PART_NUMBER"G21796-133"
VALUE"40.2K"
WATTAGE"1/16W"
TOLERANCE"1%"
PACK_TYPE"0402"
MATERIAL"CHIP";
"A"
$PN"1"52;
"B"
$PN"2"1;
%"AGND0"
"1","(-5400,450)","0","mstr_symbols","I101";
;
VOLTAGE"0"
BOM_COST"MIO_VRD_MAIN"
CDS_LIB"mstr_symbols"
BODY_TYPE"PLUMBING"
ROOM"VR_P3V3"
HDL_POWER"AGND_HSC";
"A"1;
%"RES"
"2","(-5600,750)","0","mstr_discrete","I102";
;
CDS_SEC"1"
SEC"1"
SEC_TYPE"0402"
ROOM"HOT_SWAP"
CDS_LOCATION"R1D34"
CDS_LIB"mstr_discrete"
PART_NUMBER"G21796-317"
TOLERANCE"1.0%"
LOCATION"R1D34"
VALUE"16K"
WATTAGE"1/16W"
MATERIAL"CHIP"
PACK_TYPE"0402";
"A"
$PN"1"53;
"B"
$PN"2"1;
%"CAP_A"
"1","(-6150,850)","2","dev_discrete","I105";
;
CDS_SEC"1"
$SEC"1"
ROOM"HOT_SWAP"
CDS_LIB"dev_discrete"
CDS_LOCATION"C9P15"
TOLERANCE"10%"
VALUE"0.1UF"
LOCATION"C9P15"
VOLTAGE"16V"
MATERIAL"X7R"
PACK_TYPE"0402V"
PART_NUMBER"A36096-030";
"B"
$PN"2"2;
"A"
$PN"1"47;
%"AGND0"
"1","(-6150,600)","0","mstr_symbols","I106";
;
BOM_COST"MIO_VRD_MAIN"
ROOM"VR_P3V3"
BODY_TYPE"PLUMBING"
CDS_LIB"mstr_symbols"
VOLTAGE"0"
HDL_POWER"AGND_HSC";
"A"2;
%"CAP_A"
"1","(-6075,3575)","2","dev_discrete","I107";
;
SEC"1"
SEC_TYPE"0402V"
CDS_SEC"1"
ROOM"HOT_SWAP"
CDS_LOCATION"C1D26"
CDS_LIB"dev_discrete"
LOCATION"C1D26"
PART_NUMBER"A36096-030"
VALUE"0.1UF"
TOLERANCE"10%"
PACK_TYPE"0402V"
VOLTAGE"16V"
MATERIAL"X7R";
"B"
$PN"2"8;
"A"
$PN"1"50;
%"RES"
"1","(-2050,925)","0","mstr_discrete","I108";
;
CDS_SEC"1"
SEC_TYPE"0402"
SEC"1"
CDS_LIB"mstr_discrete"
CDS_LOCATION"R1D33"
PACK_TYPE"0402"
LOCATION"R1D33"
PART_NUMBER"G21796-074"
TOLERANCE"1%"
MATERIAL"CHIP"
VALUE"33.2"
WATTAGE"1/16W";
"B"
$PN"2"32;
"A"
$PN"1"46;
%"RES"
"1","(-1700,3950)","0","mstr_discrete","I109";
;
CDS_SEC"1"
SEC_TYPE"0402"
SEC"1"
CDS_LOCATION"R1D26"
CDS_LIB"mstr_discrete"
PACK_TYPE"0402"
PART_NUMBER"G21796-074"
TOLERANCE"1%"
LOCATION"R1D26"
MATERIAL"CHIP"
VALUE"33.2"
WATTAGE"1/16W";
"B"
$PN"2"31;
"A"
$PN"1"43;
%"GND"
"1","(-2150,2275)","0","mstr_symbols","I11";
;
HDL_POWER"GND"
CDS_LIB"mstr_symbols"
VOLTAGE"0"
BODY_TYPE"PLUMBING"
SIZE"1B";
"A\NAC"3;
%"RES"
"1","(-2050,1375)","0","mstr_discrete","I110";
;
CDS_SEC"1"
SEC"1"
SEC_TYPE"0402"
CDS_LOCATION"R1D30"
CDS_LIB"mstr_discrete"
PACK_TYPE"0402"
LOCATION"R1D30"
PART_NUMBER"G21796-074"
TOLERANCE"1%"
MATERIAL"CHIP"
VALUE"33.2"
WATTAGE"1/16W";
"B"
$PN"2"33;
"A"
$PN"1"62;
%"AGND0"
"1","(-6600,-25)","0","mstr_symbols","I112";
;
VOLTAGE"0"
CDS_LIB"mstr_symbols"
BOM_COST"MIO_VRD_MAIN"
BODY_TYPE"PLUMBING"
ROOM"VR_P3V3"
HDL_POWER"AGND_HSC";
"A"4;
%"AGND0"
"1","(-7200,3250)","0","mstr_symbols","I113";
;
CDS_LIB"mstr_symbols"
ROOM"VR_P3V3"
VOLTAGE"0"
BOM_COST"MIO_VRD_MAIN"
BODY_TYPE"PLUMBING"
HDL_POWER"AGND_HSC";
"A"5;
%"AGND0"
"1","(-5525,3350)","0","mstr_symbols","I115";
;
CDS_LIB"mstr_symbols"
VOLTAGE"0"
BOM_COST"MIO_VRD_MAIN"
ROOM"VR_P3V3"
BODY_TYPE"PLUMBING"
HDL_POWER"AGND_HSC";
"A"6;
%"GND"
"1","(-5100,3400)","0","mstr_symbols","I116";
;
VOLTAGE"0"
SIZE"1B"
CDS_LIB"mstr_symbols"
HDL_POWER"GND"
BODY_TYPE"PLUMBING";
"A\NAC"7;
%"AGND0"
"1","(-6375,3275)","0","mstr_symbols","I117";
;
BOM_COST"MIO_VRD_MAIN"
CDS_LIB"mstr_symbols"
VOLTAGE"0"
ROOM"VR_P3V3"
BODY_TYPE"PLUMBING"
HDL_POWER"AGND_HSC";
"A"8;
%"AGND0"
"1","(-2375,2300)","0","mstr_symbols","I118";
;
ROOM"VR_P3V3"
CDS_LIB"mstr_symbols"
BOM_COST"MIO_VRD_MAIN"
VOLTAGE"0"
BODY_TYPE"PLUMBING"
HDL_POWER"AGND_HSC";
"A"9;
%"CAP"
"1","(-5650,2000)","0","mstr_discrete","I119";
;
CDS_SEC"1"
SEC_TYPE"0402"
SEC"1"
CDS_LOCATION"C1D19"
ROOM"HOT_SWAP"
CDS_LIB"mstr_discrete"
LOCATION"C1D19"
VALUE"1.0UF"
PART_NUMBER"D97712-011"
PACK_TYPE"0402"
TOLERANCE"10%"
VOLTAGE"16V"
MATERIAL"X6S";
"A"
$PN"1"48;
"B"
$PN"2"10;
%"RES"
"2","(-6500,4050)","0","mstr_discrete","I12";
;
CDS_SEC"1"
ROOM"HOT_SWAP"
CDS_LOCATION"R9P29"
SEC"1"
SEC_TYPE"0402"
CDS_LIB"mstr_discrete"
LOCATION"R9P29"
VALUE"100.0K"
TOLERANCE"1%"
PART_NUMBER"G21796-010"
PACK_TYPE"0402"
MATERIAL"CHIP"
WATTAGE"1/16W";
"A"
$PN"1"25;
"B"
$PN"2"50;
%"AGND0"
"1","(-5650,1800)","0","mstr_symbols","I120";
;
BOM_COST"MIO_VRD_MAIN"
VOLTAGE"0"
CDS_LIB"mstr_symbols"
ROOM"VR_P3V3"
BODY_TYPE"PLUMBING"
HDL_POWER"AGND_HSC";
"A"10;
%"CAP_A"
"1","(-5000,425)","2","dev_discrete","I121";
;
ROOM"HOT_SWAP"
CDS_LOCATION"C1D21"
CDS_SEC"1"
SEC_TYPE"0402V"
SEC"1"
CDS_LIB"dev_discrete"
LOCATION"C1D21"
PART_NUMBER"A36096-030"
VALUE"0.1UF"
TOLERANCE"10%"
PACK_TYPE"0402V"
VOLTAGE"16V"
MATERIAL"X7R";
"B"
$PN"2"11;
"A"
$PN"1"52;
%"AGND0"
"1","(-5000,100)","0","mstr_symbols","I122";
;
VOLTAGE"0"
CDS_LIB"mstr_symbols"
BOM_COST"MIO_VRD_MAIN"
BODY_TYPE"PLUMBING"
ROOM"VR_P3V3"
HDL_POWER"AGND_HSC";
"A"11;
%"CONN3_C95678002"
"1","(-7750,250)","0","mstr_conn","I123";
;
CDS_SEC"1"
BOM_COST"SM_CONTROLLER"
SEC_TYPE"PIP"
SEC"1"
PACK_TYPE"PIP"
ROOM"SMBUS"
CDS_LOCATION"J1B3"
CDS_LIB"mstr_conn"
PART_NUMBER"C95678-002"
LOCATION"J1B3"
MATERIAL"CONN";
"IO1 \B"
$PN"1"68;
"IO2 \B"
$PN"2"69;
"IO3 \B"
$PN"3"64;
%"SCONN3_D53458001"
"2","(-7750,675)","0","mstr_sconn","I124";
;
CDS_SEC"1"
CDS_LOCATION"J1B4"
SEC"1"
SEC_TYPE"SM"
PACK_TYPE"SM"
CDS_LIB"mstr_sconn"
MATERIAL"EMPTY"
PART_NUMBER"D53458-001"
LOCATION"J1B4";
"IO3"
$PN"3"64;
"IO2"
$PN"2"69;
"IO1"
$PN"1"68;
%"RES"
"2","(-6500,3600)","0","mstr_discrete","I13";
;
CDS_SEC"1"
SEC_TYPE"0402"
SEC"1"
CDS_LOCATION"R1D42"
ROOM"HOT_SWAP"
CDS_LIB"mstr_discrete"
LOCATION"R1D42"
VALUE"11K"
TOLERANCE"1%"
WATTAGE"1/16W"
MATERIAL"CHIP"
PACK_TYPE"0402"
PART_NUMBER"G21796-220";
"A"
$PN"1"50;
"B"
$PN"2"8;
%"RES"
"2","(-6600,1450)","0","mstr_discrete","I15";
;
CDS_SEC"1"
SEC_TYPE"0402"
SEC"1"
CDS_LOCATION"R1D37"
NO_XNET_CONNECTION"1"
ROOM"HOT_SWAP"
CDS_LIB"mstr_discrete"
LOCATION"R1D37"
VALUE"100.0K"
PART_NUMBER"G21796-010"
MATERIAL"CHIP"
TOLERANCE"1%"
WATTAGE"1/16W"
PACK_TYPE"0402";
"A"
$PN"1"48;
"B"
$PN"2"47;
%"RES"
"2","(-5300,1425)","0","mstr_discrete","I16";
;
CDS_SEC"1"
ROOM"HOT_SWAP"
NO_XNET_CONNECTION"1"
CDS_LOCATION"R1D39"
SEC"1"
SEC_TYPE"0402"
CDS_LIB"mstr_discrete"
LOCATION"R1D39"
PART_NUMBER"G21796-010"
VALUE"100.0K"
WATTAGE"1/16W"
MATERIAL"CHIP"
TOLERANCE"1%"
PACK_TYPE"0402";
"A"
$PN"1"48;
"B"
$PN"2"52;
%"RES"
"2","(-5600,1400)","0","mstr_discrete","I17";
;
CDS_SEC"1"
SEC_TYPE"0402"
SEC"1"
NO_XNET_CONNECTION"1"
ROOM"HOT_SWAP"
CDS_LOCATION"R1D32"
CDS_LIB"mstr_discrete"
LOCATION"R1D32"
PART_NUMBER"G21796-010"
WATTAGE"1/16W"
MATERIAL"CHIP"
TOLERANCE"1%"
VALUE"100.0K"
PACK_TYPE"0402";
"A"
$PN"1"48;
"B"
$PN"2"53;
%"AGND0"
"1","(-2750,150)","0","mstr_symbols","I18";
;
ROOM"VR_P3V3"
BODY_TYPE"PLUMBING"
BOM_COST"MIO_VRD_MAIN"
CDS_LIB"mstr_symbols"
VOLTAGE"0"
HDL_POWER"AGND_HSC";
"A"12;
%"RES"
"1","(-3025,300)","0","mstr_discrete","I19";
;
CDS_SEC"1"
CDS_LIB"mstr_discrete"
SEC_TYPE"0805"
SEC"1"
ROOM"HOT_SWAP"
CDS_LOCATION"R1D41"
TOLERANCE"5%"
MATERIAL"CHIP"
LOCATION"R1D41"
PART_NUMBER"G22179-004"
VALUE"0.0"
PACK_TYPE"0805"
WATTAGE"1/8W";
"B"
$PN"2"12;
"A"
$PN"1"13;
%"RES"
"2","(-5525,4025)","0","mstr_discrete","I2";
;
CDS_SEC"1"
SEC_TYPE"0603"
SEC"1"
CDS_LOCATION"R9P30"
ROOM"HOT_SWAP"
CDS_LIB"mstr_discrete"
LOCATION"R9P30"
VALUE"10.0"
PART_NUMBER"G22026-041"
PACK_TYPE"0603"
MATERIAL"CHIP"
WATTAGE"1/10W"
TOLERANCE"1%";
"A"
$PN"1"25;
"B"
$PN"2"54;
%"GND"
"1","(-3300,150)","0","mstr_symbols","I20";
;
HDL_POWER"GND"
CDS_LIB"mstr_symbols"
SIZE"1B"
VOLTAGE"0"
BODY_TYPE"PLUMBING";
"A\NAC"13;
%"AGND0"
"1","(-2000,2375)","0","mstr_symbols","I21";
;
CDS_LIB"mstr_symbols"
BODY_TYPE"PLUMBING"
ROOM"VR_P3V3"
BOM_COST"MIO_VRD_MAIN"
VOLTAGE"0"
HDL_POWER"AGND_HSC";
"A"14;
%"AGND0"
"1","(-4725,625)","0","mstr_symbols","I23";
;
VOLTAGE"0"
CDS_LIB"mstr_symbols"
BOM_COST"MIO_VRD_MAIN"
ROOM"VR_P3V3"
BODY_TYPE"PLUMBING"
HDL_POWER"AGND_HSC";
"A"15;
%"CAP"
"1","(-4850,1500)","0","mstr_discrete","I24";
;
CDS_SEC"1"
SEC_TYPE"0603LF"
SEC"1"
CDS_LOCATION"C9P14"
ROOM"HOT_SWAP"
CDS_LIB"mstr_discrete"
PART_NUMBER"603269-064"
VALUE"0.033UF"
LOCATION"C9P14"
TOLERANCE"10%"
PACK_TYPE"0603LF"
VOLTAGE"50V"
MATERIAL"X7R";
"A"
$PN"1"60;
"B"
$PN"2"15;
%"RES"
"2","(-4625,1025)","0","mstr_discrete","I26";
;
CDS_SEC"1"
ROOM"HOT_SWAP"
SEC_TYPE"0402"
CDS_LOCATION"R1D28"
SEC"1"
CDS_LIB"mstr_discrete"
VALUE"100.0"
LOCATION"R1D28"
TOLERANCE"1%"
WATTAGE"1/16W"
PART_NUMBER"G21796-017"
PACK_TYPE"0402"
MATERIAL"EMPTY";
"A"
$PN"1"56;
"B"
$PN"2"15;
%"RES"
"1","(-5600,2725)","0","mstr_discrete","I27";
;
CDS_SEC"1"
PACK_TYPE"0402"
CDS_LOCATION"R1D24"
CDS_LIB"mstr_discrete"
WATTAGE"1/16W"
TOLERANCE"5%"
PART_NUMBER"G21497-005"
SEC_TYPE"0402"
SEC"1"
ROOM"HOT_SWAP"
LOCATION"R1D24"
MATERIAL"CHIP"
VALUE"0.0";
"B"
$PN"2"61;
"A"
$PN"1"65;
%"RES"
"1","(-5600,2675)","0","mstr_discrete","I28";
;
CDS_SEC"1"
CDS_LOCATION"R1D25"
CDS_LIB"mstr_discrete"
SEC_TYPE"0402"
SEC"1"
ROOM"HOT_SWAP"
LOCATION"R1D25"
PACK_TYPE"0402"
TOLERANCE"5%"
MATERIAL"CHIP"
VALUE"0.0"
WATTAGE"1/16W"
PART_NUMBER"G21497-005";
"B"
$PN"2"59;
"A"
$PN"1"66;
%"CAP"
"1","(-5525,3600)","0","mstr_discrete","I3";
;
CDS_SEC"1"
SEC_TYPE"0402"
ROOM"HOT_SWAP"
CDS_LOCATION"C1D25"
SEC"1"
CDS_LIB"mstr_discrete"
LOCATION"C1D25"
VALUE"1.0UF"
VOLTAGE"16V"
PACK_TYPE"0402"
PART_NUMBER"D97712-011"
MATERIAL"X6S"
TOLERANCE"10%";
"A"
$PN"1"54;
"B"
$PN"2"6;
%"RES"
"2","(-8000,2375)","0","mstr_discrete","I33";
;
CDS_SEC"1"
SEC"1"
SEC_TYPE"0402"
ROOM"HOT_SWAP"
CDS_LIB"mstr_discrete"
CDS_LOCATION"R9P17"
VALUE"150.0K"
PART_NUMBER"G21796-109"
LOCATION"R9P17"
TOLERANCE"1%"
PACK_TYPE"0402"
MATERIAL"CHIP"
WATTAGE"1/16W";
"A"
$PN"1"55;
"B"
$PN"2"16;
%"AGND0"
"1","(-7675,2075)","0","mstr_symbols","I34";
;
VOLTAGE"0"
CDS_LIB"mstr_symbols"
BOM_COST"MIO_VRD_MAIN"
ROOM"VR_P3V3"
BODY_TYPE"PLUMBING"
HDL_POWER"AGND_HSC";
"A"16;
%"RES"
"2","(-7675,2375)","0","mstr_discrete","I36";
;
CDS_SEC"1"
SEC_TYPE"0402"
SEC"1"
CDS_LIB"mstr_discrete"
CDS_LOCATION"R9P16"
ROOM"HOT_SWAP"
PART_NUMBER"G21497-005"
VALUE"0.0"
LOCATION"R9P16"
WATTAGE"1/16W"
TOLERANCE"5%"
PACK_TYPE"0402"
MATERIAL"CHIP";
"A"
$PN"1"58;
"B"
$PN"2"16;
%"RES"
"2","(-8000,2825)","0","mstr_discrete","I37";
;
CDS_SEC"1"
SEC_TYPE"0402"
SEC"1"
NO_XNET_CONNECTION"1"
ROOM"HOT_SWAP"
CDS_LOCATION"R1D29"
CDS_LIB"mstr_discrete"
TOLERANCE"1%"
WATTAGE"1/16W"
MATERIAL"EMPTY"
LOCATION"R1D29"
PART_NUMBER"G21796-072"
VALUE"4.75K"
PACK_TYPE"0402";
"A"
$PN"1"48;
"B"
$PN"2"55;
%"RES"
"2","(-7675,2850)","0","mstr_discrete","I38";
;
CDS_SEC"1"
ROOM"HOT_SWAP"
NO_XNET_CONNECTION"1"
SEC"1"
SEC_TYPE"0402"
CDS_LOCATION"R1D27"
CDS_LIB"mstr_discrete"
MATERIAL"EMPTY"
PART_NUMBER"G21796-072"
WATTAGE"1/16W"
TOLERANCE"1%"
LOCATION"R1D27"
VALUE"4.75K"
PACK_TYPE"0402";
"A"
$PN"1"48;
"B"
$PN"2"58;
%"RES"
"2","(-3125,1075)","2","mstr_discrete","I41";
;
CDS_SEC"1"
SEC_TYPE"0402"
SEC"1"
BOM_COST"MIO_USB"
ROOM"HOT_SWAP"
CDS_LOCATION"R9P18"
CDS_LIB"mstr_discrete"
LOCATION"R9P18"
VALUE"15.0K"
TOLERANCE"1%"
WATTAGE"1/16W"
PACK_TYPE"0402"
MATERIAL"CHIP"
PART_NUMBER"G21796-107";
"A"
$PN"1"24;
"B"
$PN"2"46;
%"RES"
"2","(-2825,750)","2","mstr_discrete","I43";
;
CDS_SEC"1"
ROOM"HOT_SWAP"
SEC"1"
SEC_TYPE"0402"
CDS_LOCATION"R1D31"
CDS_LIB"mstr_discrete"
TOLERANCE"1%"
VALUE"6.19K"
PACK_TYPE"0402"
MATERIAL"CHIP"
WATTAGE"1/16W"
LOCATION"R1D31"
PART_NUMBER"G21796-161";
"A"
$PN"1"46;
"B"
$PN"2"17;
%"GND"
"1","(-2825,550)","0","mstr_symbols","I44";
;
VOLTAGE"0"
CDS_LIB"mstr_symbols"
HDL_POWER"GND"
SIZE"1B"
BODY_TYPE"PLUMBING";
"A\NAC"17;
%"AGND0"
"1","(-7025,1975)","0","mstr_symbols","I52";
;
VOLTAGE"0"
BOM_COST"MIO_VRD_MAIN"
CDS_LIB"mstr_symbols"
BODY_TYPE"PLUMBING"
ROOM"VR_P3V3"
HDL_POWER"AGND_HSC";
"A"18;
%"CAP_A"
"1","(-7025,2175)","2","dev_discrete","I53";
;
SEC"1"
SEC_TYPE"0402V"
CDS_SEC"1"
ROOM"HOT_SWAP"
CDS_LIB"dev_discrete"
CDS_LOCATION"C1D11"
MATERIAL"X7R"
VOLTAGE"16V"
TOLERANCE"10%"
LOCATION"C1D11"
VALUE"0.1UF"
PART_NUMBER"A36096-030"
PACK_TYPE"0402V";
"B"
$PN"2"18;
"A"
$PN"1"29;
%"RES"
"2","(-6725,2025)","0","mstr_discrete","I54";
;
CDS_SEC"1"
SEC"1"
SEC_TYPE"0402"
ROOM"HOT_SWAP"
CDS_LOCATION"R9P23"
CDS_LIB"mstr_discrete"
LOCATION"R9P23"
VALUE"100.0K"
TOLERANCE"1%"
PART_NUMBER"G21796-010"
PACK_TYPE"0402"
MATERIAL"CHIP"
WATTAGE"1/16W";
"A"
$PN"1"23;
"B"
$PN"2"51;
%"RES"
"2","(-6725,1725)","2","mstr_discrete","I55";
;
CDS_SEC"1"
SEC_TYPE"0402"
SEC"1"
BOM_COST"MIO_USB"
ROOM"HOT_SWAP"
CDS_LOCATION"R9P24"
CDS_LIB"mstr_discrete"
TOLERANCE"1%"
PACK_TYPE"0402"
MATERIAL"CHIP"
WATTAGE"1/16W"
LOCATION"R9P24"
PART_NUMBER"G21796-089"
VALUE"12.1K";
"A"
$PN"1"51;
"B"
$PN"2"19;
%"AGND0"
"1","(-6725,1525)","0","mstr_symbols","I56";
;
VOLTAGE"0"
CDS_LIB"mstr_symbols"
BOM_COST"MIO_VRD_MAIN"
ROOM"VR_P3V3"
BODY_TYPE"PLUMBING"
HDL_POWER"AGND_HSC";
"A"19;
%"NPN"
"1","(-1650,1650)","0","mstr_discrete","I58";
;
CDS_SEC"1"
SEC_TYPE"SM"
SEC"1"
CDS_LOCATION"Q1D3"
ROOM"HOT_SWAP"
CDS_LIB"mstr_discrete"
LOCATION"Q1D3"
PART_NUMBER"C52245-001"
VALUE"MMBT3904"
PACK_TYPE"SM"
MATERIAL"IC";
"C"
$PN"3"34;
"E"
$PN"2"20;
"B"
$PN"1"34;
%"GND"
"1","(-1600,1450)","0","mstr_symbols","I59";
;
SIZE"1B"
HDL_POWER"GND"
BODY_TYPE"PLUMBING"
CDS_LIB"mstr_symbols"
VOLTAGE"0";
"A\NAC"20;
%"RES"
"2","(-7200,4025)","0","mstr_discrete","I6";
;
CDS_SEC"1"
ROOM"HOT_SWAP"
SEC"1"
CDS_LOCATION"R9P28"
SEC_TYPE"0402"
CDS_LIB"mstr_discrete"
LOCATION"R9P28"
VALUE"100.0K"
PART_NUMBER"G21796-010"
TOLERANCE"1%"
PACK_TYPE"0402"
MATERIAL"CHIP"
WATTAGE"1/16W";
"A"
$PN"1"25;
"B"
$PN"2"49;
%"RES"
"2","(-400,3025)","0","mstr_discrete","I65";
;
CDS_SEC"1"
SEC_TYPE"0402"
BOM_COST"MIO_USB"
CDS_LOCATION"R1D36"
SEC"1"
ROOM"HOT_SWAP"
CDS_LIB"mstr_discrete"
VALUE"1.00K"
LOCATION"R1D36"
TOLERANCE"1%"
PART_NUMBER"G21796-026"
PACK_TYPE"0402"
MATERIAL"CHIP"
WATTAGE"1/16W";
"A"
$PN"1"22;
"B"
$PN"2"30;
%"CAP_A"
"1","(-400,2625)","0","dev_discrete","I67";
;
CDS_SEC"1"
SEC_TYPE"0402V"
SEC"1"
ROOM"HOT_SWAP"
CDS_LOCATION"C9P12"
CDS_LIB"dev_discrete"
LOCATION"C9P12"
VALUE"0.1UF"
TOLERANCE"10%"
VOLTAGE"16V"
MATERIAL"EMPTY"
PART_NUMBER"A36096-030"
PACK_TYPE"0402V";
"B"
$PN"2"21;
"A"
$PN"1"30;
%"AGND0"
"1","(-400,2400)","0","mstr_symbols","I68";
;
BOM_COST"MIO_VRD_MAIN"
VOLTAGE"0"
CDS_LIB"mstr_symbols"
BODY_TYPE"PLUMBING"
ROOM"VR_P3V3"
HDL_POWER"AGND_HSC";
"A"21;
%"CAP_A"
"1","(-6775,3575)","2","dev_discrete","I7";
;
CDS_LOCATION"C1D27"
ROOM"HOT_SWAP"
CDS_SEC"1"
SEC_TYPE"0402V"
SEC"1"
CDS_LIB"dev_discrete"
LOCATION"C1D27"
VALUE"0.1UF"
VOLTAGE"16V"
MATERIAL"X7R"
PACK_TYPE"0402V"
TOLERANCE"10%"
PART_NUMBER"A36096-030";
"B"
$PN"2"5;
"A"
$PN"1"49;
%"P12V_STBY"
"1","(-400,3600)","0","mstr_symbols","I75";
;
SIZE"1B"
CDS_LIB"mstr_symbols"
VOLTAGE"12.0V"
BODY_TYPE"PLUMBING"
HDL_POWER"P12V_STBY";
"G\NAC"22;
%"P12V_STBY"
"1","(-6725,2250)","0","mstr_symbols","I76";
;
BODY_TYPE"PLUMBING"
CDS_LIB"mstr_symbols"
SIZE"1B"
VOLTAGE"12.0V"
HDL_POWER"P12V_STBY";
"G\NAC"23;
%"P12V_STBY"
"1","(-3125,1275)","0","mstr_symbols","I77";
;
SIZE"1B"
CDS_LIB"mstr_symbols"
VOLTAGE"12.0V"
BODY_TYPE"PLUMBING"
HDL_POWER"P12V_STBY";
"G\NAC"24;
%"P12V_PSU"
"1","(-6675,4425)","0","mstr_symbols","I79";
;
HDL_POWER"P12V_PSU"
ROOM"P2V5_LAN_AUX_VR"
BODY_TYPE"PLUMBING"
CDS_LIB"mstr_symbols"
BOM_COST"NT_BASE_VRD"
VOLTAGE"12.0";
"G\NAC"25;
%"FET_N_DUAL"
"5","(-6600,400)","0","mstr_discrete","I82";
;
CDS_SEC"2"
ROOM"HOT_SWAP"
SEC_TYPE"SMLF"
SEC"2"
PACK_TYPE"SMLF"
CDS_LOCATION"Q1D1"
CDS_LIB"mstr_discrete"
LOCATION"Q1D1"
PART_NUMBER"D24280-001"
VALUE"2N7002DW"
MATERIAL"FET";
"GATE <SIZE -1..0>"
$PN"5"68;
"SOURCE <SIZE-1..0>"
$PN"4"4;
"DRAIN <SIZE -1..0>"
$PN"3"67;
%"AGND0"
"1","(-5875,-25)","0","mstr_symbols","I83";
;
VOLTAGE"0"
CDS_LIB"mstr_symbols"
BOM_COST"MIO_VRD_MAIN"
BODY_TYPE"PLUMBING"
ROOM"VR_P3V3"
HDL_POWER"AGND_HSC";
"A"26;
%"RES"
"1","(-6600,925)","1","mstr_discrete","I84";
;
CDS_SEC"1"
NO_XNET_CONNECTION"1"
SEC"1"
SEC_TYPE"0402"
CDS_LOCATION"R1D13"
CDS_LIB"mstr_discrete"
ROOM"HOT_SWAP"
LOCATION"R1D13"
PART_NUMBER"G21796-058"
PACK_TYPE"0402"
MATERIAL"CHIP"
TOLERANCE"1%"
WATTAGE"1/16W"
VALUE"90.9K";
"B"
$PN"2"47;
"A"
$PN"1"67;
%"RES"
"2","(-5875,875)","0","mstr_discrete","I85";
;
CDS_SEC"1"
ROOM"HOT_SWAP"
NO_XNET_CONNECTION"1"
SEC"1"
SEC_TYPE"0402"
CDS_LOCATION"R1D16"
CDS_LIB"mstr_discrete"
LOCATION"R1D16"
PART_NUMBER"G21796-007"
WATTAGE"1/16W"
TOLERANCE"1%"
VALUE"69.8K"
PACK_TYPE"0402"
MATERIAL"CHIP";
"A"
$PN"1"47;
"B"
$PN"2"63;
%"FET_N_DUAL"
"5","(-5875,275)","0","mstr_discrete","I86";
;
CDS_SEC"1"
ROOM"HOT_SWAP"
CDS_LOCATION"Q1D1"
SEC"1"
SEC_TYPE"SMLF"
CDS_LIB"mstr_discrete"
PACK_TYPE"SMLF"
LOCATION"Q1D1"
PART_NUMBER"D24280-001"
VALUE"2N7002DW"
MATERIAL"FET";
"GATE <SIZE -1..0>"
$PN"2"64;
"SOURCE <SIZE-1..0>"
$PN"1"26;
"DRAIN <SIZE -1..0>"
$PN"6"63;
%"RES"
"2","(-6950,-50)","0","mstr_discrete","I87";
;
CDS_SEC"1"
ROOM"HOT_SWAP"
CDS_LOCATION"R1D18"
SEC"1"
SEC_TYPE"0402"
CDS_LIB"mstr_discrete"
VALUE"100.0K"
LOCATION"R1D18"
TOLERANCE"1%"
PART_NUMBER"G21796-010"
PACK_TYPE"0402"
MATERIAL"CHIP"
WATTAGE"1/16W";
"A"
$PN"1"68;
"B"
$PN"2"27;
%"RES"
"2","(-6300,-50)","0","mstr_discrete","I88";
;
CDS_SEC"1"
SEC_TYPE"0402"
SEC"1"
CDS_LOCATION"R1D11"
ROOM"HOT_SWAP"
CDS_LIB"mstr_discrete"
LOCATION"R1D11"
VALUE"100.0K"
TOLERANCE"1%"
PART_NUMBER"G21796-010"
PACK_TYPE"0402"
MATERIAL"CHIP"
WATTAGE"1/16W";
"A"
$PN"1"64;
"B"
$PN"2"27;
%"AGND0"
"1","(-6300,-325)","0","mstr_symbols","I89";
;
VOLTAGE"0"
BOM_COST"MIO_VRD_MAIN"
CDS_LIB"mstr_symbols"
BODY_TYPE"PLUMBING"
ROOM"VR_P3V3"
HDL_POWER"AGND_HSC";
"A"27;
%"RES"
"2","(-7200,3625)","0","mstr_discrete","I9";
;
CDS_SEC"1"
SEC_TYPE"0402"
SEC"1"
CDS_LOCATION"R1D43"
ROOM"HOT_SWAP"
CDS_LIB"mstr_discrete"
WATTAGE"1/16W"
TOLERANCE"1%"
VALUE"7.5K"
LOCATION"R1D43"
PART_NUMBER"G21796-177"
MATERIAL"CHIP"
PACK_TYPE"0402";
"A"
$PN"1"49;
"B"
$PN"2"5;
%"P12V_PSU"
"1","(-7300,950)","0","mstr_symbols","I90";
;
ROOM"P2V5_LAN_AUX_VR"
BOM_COST"NT_BASE_VRD"
HDL_POWER"P12V_PSU"
VOLTAGE"12.0"
CDS_LIB"mstr_symbols"
BODY_TYPE"PLUMBING";
"G\NAC"28;
%"RES"
"2","(-7300,750)","0","mstr_discrete","I92";
;
CDS_SEC"1"
ROOM"HOT_SWAP"
CDS_LOCATION"R1D15"
SEC"1"
SEC_TYPE"0402"
CDS_LIB"mstr_discrete"
LOCATION"R1D15"
PART_NUMBER"G21796-010"
VALUE"100.0K"
PACK_TYPE"0402"
MATERIAL"CHIP"
WATTAGE"1/16W"
TOLERANCE"1%";
"A"
$PN"1"28;
"B"
$PN"2"69;
%"ZENER"
"4","(-5100,3875)","0","mstr_discrete","I99";
;
CDS_SEC"1"
SEC_TYPE"SM"
CDS_LIB"mstr_discrete"
SEC"1"
CDS_LOCATION"VR1D1"
PART_NUMBER"H69095-001"
LOCATION"VR1D1"
VALUE"13V"
MATERIAL"IC"
PACK_TYPE"SM";
"C"
$PN"1"25;
"A"
$PN"2"7;
END.
